(kicad_pcb
	(version 20260206)
	(generator "pcbnew")
	(generator_version "10.0")
	(general
		(thickness 1.6)
		(legacy_teardrops no)
	)
	(paper "A4")
	(title_block
		(title "baseboard — 13948-1b.1110WZS1818.brd")
		(comment 1 "Honey Badger (Wiwynn) / footprints 1443-1450 of 2523")
	)
	(layers
		(0 "F.Cu" signal "TOP")
		(4 "In1.Cu" signal "L2GND")
		(6 "In2.Cu" signal "L3")
		(8 "In3.Cu" signal "L4VCC")
		(10 "In4.Cu" signal "L5VCC")
		(12 "In5.Cu" signal "L6")
		(14 "In6.Cu" signal "L7GND")
		(2 "B.Cu" signal "BOTTOM")
		(9 "F.Adhes" user "F.Adhesive")
		(11 "B.Adhes" user "B.Adhesive")
		(13 "F.Paste" user "Package Geometry/Pastemask Top")
		(15 "B.Paste" user "Package Geometry/Pastemask Bottom")
		(5 "F.SilkS" user "Ref Des/Silkscreen Top")
		(7 "B.SilkS" user "Ref Des/Silkscreen Bottom")
		(1 "F.Mask" user "Board Geometry/Soldermask Top")
		(3 "B.Mask" user "Board Geometry/Soldermask Bottom")
		(17 "Dwgs.User" user "User.Drawings")
		(19 "Cmts.User" user "User.Comments")
		(21 "Eco1.User" user "User.Eco1")
		(23 "Eco2.User" user "User.Eco2")
		(25 "Edge.Cuts" user "Board Geometry/Outline")
		(27 "Margin" user)
		(31 "F.CrtYd" user "Package Geometry/Place Bound Top")
		(29 "B.CrtYd" user "Package Geometry/Place Bound Bottom")
		(35 "F.Fab" user "Ref Des/Assembly Top")
		(33 "B.Fab" user "Ref Des/Assembly Bottom")
	)
	(footprint ""
		(layer "F.Cu")
		(at 143.65097 -83.439 90)
		(property "Reference" "C327"
			(at 0 0 90)
			(layer "F.SilkS")
			(hide yes)
			(effects
				(font
					(size 1.27 1.27)
				)
			)
		)
		(property "Value" "SCD1U16V2KX-3GP"
			(at 1.1811 -2.7051 90)
			(unlocked yes)
			(layer "F.Fab")
			(hide yes)
			(effects
				(font
					(size 1.016 1.016)
					(thickness 0.1524)
				)
			)
		)
		(property "Device Type" "C402H22"
			(at 1.1811 -4.2291 90)
			(unlocked yes)
			(layer "F.Fab")
			(hide yes)
			(effects
				(font
					(size 1.016 1.016)
					(thickness 0.1524)
				)
			)
		)
		(duplicate_pad_numbers_are_jumpers no)
		(fp_rect
			(start -0.4318 0.9525)
			(end 0.4318 -0.9525)
			(stroke
				(width 0)
				(type default)
			)
			(fill no)
			(layer "F.CrtYd")
		)
		(fp_rect
			(start -0.4318 0.9525)
			(end 0.4318 -0.9525)
			(stroke
				(width 0)
				(type default)
			)
			(fill no)
			(layer "F.Fab")
		)
		(pad "1" smd custom
			(at 0 -0.4445 90)
			(size 0.1524 0.1524)
			(layers "F.Cu" "F.Mask" "F.Paste")
			(net "P3V3_STBY")
			(options
				(clearance outline)
				(anchor circle)
			)
			(primitives
				(gr_poly
					(pts
						(arc
							(start 0.3048 -0.2032)
							(mid 0.275042 -0.275042)
							(end 0.2032 -0.3048)
						)
						(arc
							(start -0.2032 -0.3048)
							(mid -0.275042 -0.275042)
							(end -0.3048 -0.2032)
						)
						(arc
							(start -0.3048 0.2032)
							(mid -0.275042 0.275042)
							(end -0.2032 0.3048)
						)
						(arc
							(start 0.2032 0.3048)
							(mid 0.275042 0.275042)
							(end 0.3048 0.2032)
						)
					)
					(width 0)
					(fill yes)
				)
			)
		)
		(pad "2" smd custom
			(at 0 0.4445 90)
			(size 0.1524 0.1524)
			(layers "F.Cu" "F.Mask" "F.Paste")
			(net "GND")
			(options
				(clearance outline)
				(anchor circle)
			)
			(primitives
				(gr_poly
					(pts
						(arc
							(start 0.3048 -0.2032)
							(mid 0.275042 -0.275042)
							(end 0.2032 -0.3048)
						)
						(arc
							(start -0.2032 -0.3048)
							(mid -0.275042 -0.275042)
							(end -0.3048 -0.2032)
						)
						(arc
							(start -0.3048 0.2032)
							(mid -0.275042 0.275042)
							(end -0.2032 0.3048)
						)
						(arc
							(start 0.2032 0.3048)
							(mid 0.275042 0.275042)
							(end 0.3048 0.2032)
						)
					)
					(width 0)
					(fill yes)
				)
			)
		)
	)
	(footprint ""
		(layer "F.Cu")
		(at 266.065 -172.974 90)
		(property "Reference" "R526"
			(at 0 0 90)
			(layer "F.SilkS")
			(hide yes)
			(effects
				(font
					(size 1.27 1.27)
				)
			)
		)
		(property "Value" "0R2J-2-GP"
			(at 0.064008 -3.993896 90)
			(unlocked yes)
			(layer "F.Fab")
			(hide yes)
			(effects
				(font
					(size 1.016 1.016)
					(thickness 0.1524)
				)
			)
		)
		(property "Device Type" "R402H16"
			(at 0.064008 -5.517896 90)
			(unlocked yes)
			(layer "F.Fab")
			(hide yes)
			(effects
				(font
					(size 1.016 1.016)
					(thickness 0.1524)
				)
			)
		)
		(duplicate_pad_numbers_are_jumpers no)
		(fp_line
			(start 0.508 -0.9398)
			(end -0.508 -0.9398)
			(stroke
				(width 0.1524)
				(type default)
			)
			(layer "F.SilkS")
		)
		(fp_line
			(start -0.508 -0.9398)
			(end -0.508 0.9398)
			(stroke
				(width 0.1524)
				(type default)
			)
			(layer "F.SilkS")
		)
		(fp_rect
			(start -0.508 0.9398)
			(end 0.508 -0.9398)
			(stroke
				(width 0)
				(type default)
			)
			(fill no)
			(layer "F.CrtYd")
		)
		(fp_rect
			(start -0.508 0.9398)
			(end 0.508 -0.9398)
			(stroke
				(width 0)
				(type default)
			)
			(fill no)
			(layer "F.Fab")
		)
		(pad "1" smd custom
			(at 0 -0.4445 90)
			(size 0.1397 0.1397)
			(layers "F.Cu" "F.Mask" "F.Paste")
			(net "NIC_SMBUS_ALERT_N")
			(options
				(clearance outline)
				(anchor circle)
			)
			(primitives
				(gr_poly
					(pts
						(arc
							(start -0.1778 -0.2794)
							(mid -0.249642 -0.249642)
							(end -0.2794 -0.1778)
						)
						(arc
							(start -0.2794 0.1778)
							(mid -0.249642 0.249642)
							(end -0.1778 0.2794)
						)
						(arc
							(start 0.1778 0.2794)
							(mid 0.249642 0.249642)
							(end 0.2794 0.1778)
						)
						(arc
							(start 0.2794 -0.1778)
							(mid 0.249642 -0.249642)
							(end 0.1778 -0.2794)
						)
					)
					(width 0)
					(fill yes)
				)
			)
		)
		(pad "2" smd custom
			(at 0 0.4445 90)
			(size 0.1397 0.1397)
			(layers "F.Cu" "F.Mask" "F.Paste")
			(net "BMC_SALT4")
			(options
				(clearance outline)
				(anchor circle)
			)
			(primitives
				(gr_poly
					(pts
						(arc
							(start -0.1778 -0.2794)
							(mid -0.249642 -0.249642)
							(end -0.2794 -0.1778)
						)
						(arc
							(start -0.2794 0.1778)
							(mid -0.249642 0.249642)
							(end -0.1778 0.2794)
						)
						(arc
							(start 0.1778 0.2794)
							(mid 0.249642 0.249642)
							(end 0.2794 0.1778)
						)
						(arc
							(start 0.2794 -0.1778)
							(mid 0.249642 -0.249642)
							(end 0.1778 -0.2794)
						)
					)
					(width 0)
					(fill yes)
				)
			)
		)
	)
	(footprint ""
		(layer "F.Cu")
		(at 43.8912 -114.7572 180)
		(property "Reference" "SR850"
			(at 0 0 180)
			(layer "F.SilkS")
			(hide yes)
			(effects
				(font
					(size 1.27 1.27)
				)
			)
		)
		(property "Value" "0R2J-2-GP"
			(at 0.064008 -3.993896 180)
			(unlocked yes)
			(layer "F.Fab")
			(hide yes)
			(effects
				(font
					(size 1.016 1.016)
					(thickness 0.1524)
				)
			)
		)
		(property "Device Type" "R402H16"
			(at 0.064008 -5.517896 180)
			(unlocked yes)
			(layer "F.Fab")
			(hide yes)
			(effects
				(font
					(size 1.016 1.016)
					(thickness 0.1524)
				)
			)
		)
		(duplicate_pad_numbers_are_jumpers no)
		(fp_line
			(start 0.508 -0.9398)
			(end -0.508 -0.9398)
			(stroke
				(width 0.1524)
				(type default)
			)
			(layer "F.SilkS")
		)
		(fp_line
			(start -0.508 -0.9398)
			(end -0.508 0.9398)
			(stroke
				(width 0.1524)
				(type default)
			)
			(layer "F.SilkS")
		)
		(fp_rect
			(start -0.508 0.9398)
			(end 0.508 -0.9398)
			(stroke
				(width 0)
				(type default)
			)
			(fill no)
			(layer "F.CrtYd")
		)
		(fp_rect
			(start -0.508 0.9398)
			(end 0.508 -0.9398)
			(stroke
				(width 0)
				(type default)
			)
			(fill no)
			(layer "F.Fab")
		)
		(pad "1" smd custom
			(at 0 -0.4445 180)
			(size 0.1397 0.1397)
			(layers "F.Cu" "F.Mask" "F.Paste")
			(net "SAS_SDBRX_R")
			(options
				(clearance outline)
				(anchor circle)
			)
			(primitives
				(gr_poly
					(pts
						(arc
							(start -0.1778 -0.2794)
							(mid -0.249642 -0.249642)
							(end -0.2794 -0.1778)
						)
						(arc
							(start -0.2794 0.1778)
							(mid -0.249642 0.249642)
							(end -0.1778 0.2794)
						)
						(arc
							(start 0.1778 0.2794)
							(mid 0.249642 0.249642)
							(end 0.2794 0.1778)
						)
						(arc
							(start 0.2794 -0.1778)
							(mid 0.249642 -0.249642)
							(end 0.1778 -0.2794)
						)
					)
					(width 0)
					(fill yes)
				)
			)
		)
		(pad "2" smd custom
			(at 0 0.4445 180)
			(size 0.1397 0.1397)
			(layers "F.Cu" "F.Mask" "F.Paste")
			(net "SAS_SDBRX")
			(options
				(clearance outline)
				(anchor circle)
			)
			(primitives
				(gr_poly
					(pts
						(arc
							(start -0.1778 -0.2794)
							(mid -0.249642 -0.249642)
							(end -0.2794 -0.1778)
						)
						(arc
							(start -0.2794 0.1778)
							(mid -0.249642 0.249642)
							(end -0.1778 0.2794)
						)
						(arc
							(start 0.1778 0.2794)
							(mid 0.249642 0.249642)
							(end 0.2794 0.1778)
						)
						(arc
							(start 0.2794 -0.1778)
							(mid 0.249642 -0.249642)
							(end 0.1778 -0.2794)
						)
					)
					(width 0)
					(fill yes)
				)
			)
		)
	)
	(footprint ""
		(layer "F.Cu")
		(at 266.065 -212.598 180)
		(property "Reference" "PR85"
			(at 0 0 180)
			(layer "F.SilkS")
			(hide yes)
			(effects
				(font
					(size 1.27 1.27)
				)
			)
		)
		(property "Value" "0R6J-3-GP"
			(at -0.0508 -4.8514 180)
			(unlocked yes)
			(layer "F.Fab")
			(hide yes)
			(effects
				(font
					(size 1.016 1.016)
					(thickness 0.1524)
				)
			)
		)
		(property "Device Type" "R1206H28"
			(at 0 -6.3754 180)
			(unlocked yes)
			(layer "F.Fab")
			(hide yes)
			(effects
				(font
					(size 1.016 1.016)
					(thickness 0.1524)
				)
			)
		)
		(duplicate_pad_numbers_are_jumpers no)
		(fp_line
			(start 1.016 2.2352)
			(end -1.016 2.2352)
			(stroke
				(width 0.1524)
				(type default)
			)
			(layer "F.SilkS")
		)
		(fp_line
			(start 1.016 -2.2352)
			(end 1.016 2.2352)
			(stroke
				(width 0.1524)
				(type default)
			)
			(layer "F.SilkS")
		)
		(fp_line
			(start -1.016 2.2352)
			(end -1.016 -2.2352)
			(stroke
				(width 0.1524)
				(type default)
			)
			(layer "F.SilkS")
		)
		(fp_line
			(start -1.016 -2.2352)
			(end 1.016 -2.2352)
			(stroke
				(width 0.1524)
				(type default)
			)
			(layer "F.SilkS")
		)
		(fp_rect
			(start -1.0922 2.3114)
			(end 1.0922 -2.3114)
			(stroke
				(width 0)
				(type default)
			)
			(fill no)
			(layer "F.CrtYd")
		)
		(fp_poly
			(pts
				(xy -1.0922 -2.3114) (xy 1.0922 -2.3114) (xy 1.0922 2.3114) (xy -1.0922 2.3114)
			)
			(stroke
				(width 0)
				(type default)
			)
			(fill no)
			(layer "F.Fab")
		)
		(pad "1" smd rect
			(at 0 -1.397 180)
			(size 1.651 1.27)
			(layers "F.Cu" "F.Mask" "F.Paste")
			(net "P1V26_STBY")
		)
		(pad "2" smd rect
			(at 0 1.397 180)
			(size 1.651 1.27)
			(layers "F.Cu" "F.Mask" "F.Paste")
			(net "TPS74801_1V26_STBY_OUT")
		)
	)
	(footprint ""
		(layer "F.Cu")
		(at 281.423872 -64.461136)
		(property "Reference" "R527"
			(at 0 0 0)
			(layer "F.SilkS")
			(hide yes)
			(effects
				(font
					(size 1.27 1.27)
				)
			)
		)
		(property "Value" "1K33R3F-GP"
			(at -0.0254 -2.5146 0)
			(unlocked yes)
			(layer "F.Fab")
			(hide yes)
			(effects
				(font
					(size 1.016 1.016)
					(thickness 0.1524)
				)
			)
		)
		(property "Device Type" "R603H22"
			(at -0.0254 -4.0386 0)
			(unlocked yes)
			(layer "F.Fab")
			(hide yes)
			(effects
				(font
					(size 1.016 1.016)
					(thickness 0.1524)
				)
			)
		)
		(duplicate_pad_numbers_are_jumpers no)
		(fp_line
			(start -0.4826 0)
			(end -0.2032 0)
			(stroke
				(width 0.2032)
				(type default)
			)
			(layer "F.SilkS")
		)
		(fp_line
			(start 0.2032 0)
			(end 0.4826 0)
			(stroke
				(width 0.2032)
				(type default)
			)
			(layer "F.SilkS")
		)
		(fp_rect
			(start -0.5842 1.3335)
			(end 0.5842 -1.3335)
			(stroke
				(width 0)
				(type default)
			)
			(fill no)
			(layer "F.CrtYd")
		)
		(fp_rect
			(start -0.5842 1.3335)
			(end 0.5842 -1.3335)
			(stroke
				(width 0)
				(type default)
			)
			(fill no)
			(layer "F.Fab")
		)
		(pad "1" smd custom
			(at 0 -0.762)
			(size 0.2159 0.2159)
			(layers "F.Cu" "F.Mask" "F.Paste")
			(net "PRSNT_EN_HPIC")
			(options
				(clearance outline)
				(anchor circle)
			)
			(primitives
				(gr_poly
					(pts
						(arc
							(start -0.3302 -0.4318)
							(mid -0.402042 -0.402042)
							(end -0.4318 -0.3302)
						)
						(arc
							(start -0.4318 0.3302)
							(mid -0.402042 0.402042)
							(end -0.3302 0.4318)
						)
						(arc
							(start 0.3302 0.4318)
							(mid 0.402042 0.402042)
							(end 0.4318 0.3302)
						)
						(arc
							(start 0.4318 -0.3302)
							(mid 0.402042 -0.402042)
							(end 0.3302 -0.4318)
						)
					)
					(width 0)
					(fill yes)
				)
			)
		)
		(pad "2" smd custom
			(at 0 0.762)
			(size 0.2159 0.2159)
			(layers "F.Cu" "F.Mask" "F.Paste")
			(net "GND")
			(options
				(clearance outline)
				(anchor circle)
			)
			(primitives
				(gr_poly
					(pts
						(arc
							(start -0.3302 -0.4318)
							(mid -0.402042 -0.402042)
							(end -0.4318 -0.3302)
						)
						(arc
							(start -0.4318 0.3302)
							(mid -0.402042 0.402042)
							(end -0.3302 0.4318)
						)
						(arc
							(start 0.3302 0.4318)
							(mid 0.402042 0.402042)
							(end 0.4318 0.3302)
						)
						(arc
							(start 0.4318 -0.3302)
							(mid 0.402042 -0.402042)
							(end 0.3302 -0.4318)
						)
					)
					(width 0)
					(fill yes)
				)
			)
		)
	)
	(footprint ""
		(layer "F.Cu")
		(at 302.514 -102.108)
		(property "Reference" "R161"
			(at 0 0 0)
			(layer "F.SilkS")
			(hide yes)
			(effects
				(font
					(size 1.27 1.27)
				)
			)
		)
		(property "Value" "4K7R2F-GP"
			(at 0.064008 -3.993896 0)
			(unlocked yes)
			(layer "F.Fab")
			(hide yes)
			(effects
				(font
					(size 1.016 1.016)
					(thickness 0.1524)
				)
			)
		)
		(property "Device Type" "R402H16"
			(at 0.064008 -5.517896 0)
			(unlocked yes)
			(layer "F.Fab")
			(hide yes)
			(effects
				(font
					(size 1.016 1.016)
					(thickness 0.1524)
				)
			)
		)
		(duplicate_pad_numbers_are_jumpers no)
		(fp_line
			(start -0.508 -0.9398)
			(end -0.508 0.9398)
			(stroke
				(width 0.1524)
				(type default)
			)
			(layer "F.SilkS")
		)
		(fp_line
			(start 0.508 -0.9398)
			(end -0.508 -0.9398)
			(stroke
				(width 0.1524)
				(type default)
			)
			(layer "F.SilkS")
		)
		(fp_rect
			(start -0.508 0.9398)
			(end 0.508 -0.9398)
			(stroke
				(width 0)
				(type default)
			)
			(fill no)
			(layer "F.CrtYd")
		)
		(fp_rect
			(start -0.508 0.9398)
			(end 0.508 -0.9398)
			(stroke
				(width 0)
				(type default)
			)
			(fill no)
			(layer "F.Fab")
		)
		(pad "1" smd custom
			(at 0 -0.4445)
			(size 0.1397 0.1397)
			(layers "F.Cu" "F.Mask" "F.Paste")
			(net "P3V3_STBY")
			(options
				(clearance outline)
				(anchor circle)
			)
			(primitives
				(gr_poly
					(pts
						(arc
							(start -0.1778 -0.2794)
							(mid -0.249642 -0.249642)
							(end -0.2794 -0.1778)
						)
						(arc
							(start -0.2794 0.1778)
							(mid -0.249642 0.249642)
							(end -0.1778 0.2794)
						)
						(arc
							(start 0.1778 0.2794)
							(mid 0.249642 0.249642)
							(end 0.2794 0.1778)
						)
						(arc
							(start 0.2794 -0.1778)
							(mid 0.249642 -0.249642)
							(end 0.1778 -0.2794)
						)
					)
					(width 0)
					(fill yes)
				)
			)
		)
		(pad "2" smd custom
			(at 0 0.4445)
			(size 0.1397 0.1397)
			(layers "F.Cu" "F.Mask" "F.Paste")
			(net "TEMP_2_A1")
			(options
				(clearance outline)
				(anchor circle)
			)
			(primitives
				(gr_poly
					(pts
						(arc
							(start -0.1778 -0.2794)
							(mid -0.249642 -0.249642)
							(end -0.2794 -0.1778)
						)
						(arc
							(start -0.2794 0.1778)
							(mid -0.249642 0.249642)
							(end -0.1778 0.2794)
						)
						(arc
							(start 0.1778 0.2794)
							(mid 0.249642 0.249642)
							(end 0.2794 0.1778)
						)
						(arc
							(start 0.2794 -0.1778)
							(mid 0.249642 -0.249642)
							(end 0.1778 -0.2794)
						)
					)
					(width 0)
					(fill yes)
				)
			)
		)
	)
	(footprint ""
		(layer "F.Cu")
		(at 253.492 -122.555)
		(property "Reference" "R7905"
			(at 0 0 0)
			(layer "F.SilkS")
			(hide yes)
			(effects
				(font
					(size 1.27 1.27)
				)
			)
		)
		(property "Value" "0R2J-2-GP"
			(at 0.064008 -3.993896 0)
			(unlocked yes)
			(layer "F.Fab")
			(hide yes)
			(effects
				(font
					(size 1.016 1.016)
					(thickness 0.1524)
				)
			)
		)
		(property "Device Type" "R402H16"
			(at 0.064008 -5.517896 0)
			(unlocked yes)
			(layer "F.Fab")
			(hide yes)
			(effects
				(font
					(size 1.016 1.016)
					(thickness 0.1524)
				)
			)
		)
		(duplicate_pad_numbers_are_jumpers no)
		(fp_line
			(start -0.508 -0.9398)
			(end -0.508 0.9398)
			(stroke
				(width 0.1524)
				(type default)
			)
			(layer "F.SilkS")
		)
		(fp_line
			(start 0.508 -0.9398)
			(end -0.508 -0.9398)
			(stroke
				(width 0.1524)
				(type default)
			)
			(layer "F.SilkS")
		)
		(fp_rect
			(start -0.508 0.9398)
			(end 0.508 -0.9398)
			(stroke
				(width 0)
				(type default)
			)
			(fill no)
			(layer "F.CrtYd")
		)
		(fp_rect
			(start -0.508 0.9398)
			(end 0.508 -0.9398)
			(stroke
				(width 0)
				(type default)
			)
			(fill no)
			(layer "F.Fab")
		)
		(pad "1" smd custom
			(at 0 -0.4445)
			(size 0.1397 0.1397)
			(layers "F.Cu" "F.Mask" "F.Paste")
			(net "CPU_U193_PIN3_RX")
			(options
				(clearance outline)
				(anchor circle)
			)
			(primitives
				(gr_poly
					(pts
						(arc
							(start -0.1778 -0.2794)
							(mid -0.249642 -0.249642)
							(end -0.2794 -0.1778)
						)
						(arc
							(start -0.2794 0.1778)
							(mid -0.249642 0.249642)
							(end -0.1778 0.2794)
						)
						(arc
							(start 0.1778 0.2794)
							(mid 0.249642 0.249642)
							(end 0.2794 0.1778)
						)
						(arc
							(start 0.2794 -0.1778)
							(mid 0.249642 -0.249642)
							(end 0.1778 -0.2794)
						)
					)
					(width 0)
					(fill yes)
				)
			)
		)
		(pad "2" smd custom
			(at 0 0.4445)
			(size 0.1397 0.1397)
			(layers "F.Cu" "F.Mask" "F.Paste")
			(net "CPU_U193_PIN3_RX_R")
			(options
				(clearance outline)
				(anchor circle)
			)
			(primitives
				(gr_poly
					(pts
						(arc
							(start -0.1778 -0.2794)
							(mid -0.249642 -0.249642)
							(end -0.2794 -0.1778)
						)
						(arc
							(start -0.2794 0.1778)
							(mid -0.249642 0.249642)
							(end -0.1778 0.2794)
						)
						(arc
							(start 0.1778 0.2794)
							(mid 0.249642 0.249642)
							(end 0.2794 0.1778)
						)
						(arc
							(start 0.2794 -0.1778)
							(mid 0.249642 -0.249642)
							(end 0.1778 -0.2794)
						)
					)
					(width 0)
					(fill yes)
				)
			)
		)
	)
	(footprint ""
		(layer "F.Cu")
		(at 208.407 -94.996 -90)
		(property "Reference" "PC145"
			(at 0 0 270)
			(layer "F.SilkS")
			(hide yes)
			(effects
				(font
					(size 1.27 1.27)
				)
			)
		)
		(property "Value" "SC10U6D3V5KX-1GP"
			(at -0.0762 -6.1214 270)
			(unlocked yes)
			(layer "F.Fab")
			(hide yes)
			(effects
				(font
					(size 1.016 1.016)
					(thickness 0.1524)
				)
			)
		)
		(property "Device Type" "C805H54"
			(at -0.0762 -8.1534 270)
			(unlocked yes)
			(layer "F.Fab")
			(hide yes)
			(effects
				(font
					(size 1.016 1.016)
					(thickness 0.1524)
				)
			)
		)
		(duplicate_pad_numbers_are_jumpers no)
		(fp_line
			(start 0.635 0)
			(end -0.635 0)
			(stroke
				(width 0.508)
				(type default)
			)
			(layer "F.SilkS")
		)
		(fp_rect
			(start -0.9652 1.778)
			(end 0.9652 -1.778)
			(stroke
				(width 0)
				(type default)
			)
			(fill no)
			(layer "F.CrtYd")
		)
		(fp_poly
			(pts
				(xy -0.9652 -1.778) (xy 0.9652 -1.778) (xy 0.9652 1.778) (xy -0.9652 1.778)
			)
			(stroke
				(width 0)
				(type default)
			)
			(fill no)
			(layer "F.Fab")
		)
		(pad "1" smd rect
			(at 0 -0.9652 270)
			(size 1.397 1.143)
			(layers "F.Cu" "F.Mask" "F.Paste")
			(net "P1V5_C")
		)
		(pad "2" smd rect
			(at 0 0.9652 270)
			(size 1.397 1.143)
			(layers "F.Cu" "F.Mask" "F.Paste")
			(net "GND")
		)
	)
)
